# T6G (Grand Teton) — schematic netlist excerpt (pin names and nets, part order shuffled) for the footprints in the layout excerpt that follows; sources: Cadence DE-HDL packaged netlist, KiCad conversion of 04192023_DAF0TMB3IC0_F0TG_MB_C_brd_V02_OCP.brd

Q7001  MOSFET_NCH_1D3S  PSMNR58-30YLH EMPTY  pkg SOT1023  page 169
  \1\  = GND
  \2\  = GND
  \3\  = GND
  \4\  = P12V_AUX_DSC_G2
  \5\  = P12V_AUX_DSC

C674  Q_CAP  0.1UF 25V 10% EMPTY  pkg 0402  page 209 : A = PVDD18_S5_P0_EN ; B = GND

(kicad_pcb
	(version 20260206)
	(generator "pcbnew")
	(generator_version "10.0")
	(general
		(thickness 1.6)
		(legacy_teardrops no)
	)
	(paper "A4")
	(title_block
		(title "04192023_DAF0TMB3IC0_F0TG_MB_C_brd_V02_OCP.brd")
		(comment 1 "Grand Teton / footprints 420-421 of 8354")
	)
	(layers
		(0 "F.Cu" signal "TOP")
		(4 "In1.Cu" signal "GND")
		(6 "In2.Cu" signal "IN1")
		(8 "In3.Cu" signal "GND1")
		(10 "In4.Cu" signal "IN2")
		(12 "In5.Cu" signal "GND2")
		(14 "In6.Cu" signal "IN3")
		(16 "In7.Cu" signal "GND3")
		(18 "In8.Cu" signal "VCC")
		(20 "In9.Cu" signal "VCC1")
		(22 "In10.Cu" signal "GND4")
		(24 "In11.Cu" signal "IN4")
		(26 "In12.Cu" signal "GND5")
		(28 "In13.Cu" signal "IN5")
		(30 "In14.Cu" signal "GND6")
		(32 "In15.Cu" signal "IN6")
		(34 "In16.Cu" signal "GND7")
		(2 "B.Cu" signal "BOTTOM")
		(9 "F.Adhes" user "F.Adhesive")
		(11 "B.Adhes" user "B.Adhesive")
		(13 "F.Paste" user "Package Geometry/Pastemask Top")
		(15 "B.Paste" user "Package Geometry/Pastemask Bottom")
		(5 "F.SilkS" user "Ref Des/Silkscreen Top")
		(7 "B.SilkS" user "Ref Des/Silkscreen Bottom")
		(1 "F.Mask" user "Board Geometry/Soldermask Top")
		(3 "B.Mask" user "Board Geometry/Soldermask Bottom")
		(17 "Dwgs.User" user "User.Drawings")
		(19 "Cmts.User" user "User.Comments")
		(21 "Eco1.User" user "User.Eco1")
		(23 "Eco2.User" user "User.Eco2")
		(25 "Edge.Cuts" user "Board Geometry/Outline")
		(27 "Margin" user)
		(31 "F.CrtYd" user "Package Geometry/Place Bound Top")
		(29 "B.CrtYd" user "Package Geometry/Place Bound Bottom")
		(35 "F.Fab" user "Ref Des/Assembly Top")
		(33 "B.Fab" user "Ref Des/Assembly Bottom")
	)
	(footprint ""
		(layer "F.Cu")
		(at 329.877928 -137.575036 180)
		(property "Reference" "C674"
			(at 0 0 180)
			(layer "F.SilkS")
			(hide yes)
			(effects
				(font
					(size 1.27 1.27)
				)
			)
		)
		(property "Value" ""
			(at 0 0 180)
			(layer "F.Fab")
			(effects
				(font
					(size 1.27 1.27)
				)
			)
		)
		(duplicate_pad_numbers_are_jumpers no)
		(fp_line
			(start 0.7874 0.4064)
			(end -0.7874 0.4064)
			(stroke
				(width 0.1524)
				(type default)
			)
			(layer "F.SilkS")
		)
		(fp_line
			(start 0.7874 -0.4064)
			(end 0.7874 0.4064)
			(stroke
				(width 0.1524)
				(type default)
			)
			(layer "F.SilkS")
		)
		(fp_line
			(start -0.7874 0.4064)
			(end -0.7874 -0.4064)
			(stroke
				(width 0.1524)
				(type default)
			)
			(layer "F.SilkS")
		)
		(fp_line
			(start -0.7874 -0.4064)
			(end 0.7874 -0.4064)
			(stroke
				(width 0.1524)
				(type default)
			)
			(layer "F.SilkS")
		)
		(fp_line
			(start 0.67945 0.3048)
			(end 0.120396 0.3048)
			(stroke
				(width 0.1)
				(type default)
			)
			(layer "F.Fab")
		)
		(fp_line
			(start 0.67945 -0.3048)
			(end 0.67945 0.3048)
			(stroke
				(width 0.1)
				(type default)
			)
			(layer "F.Fab")
		)
		(fp_line
			(start 0.12065 -0.2794)
			(end 0.12065 -0.3048)
			(stroke
				(width 0.1)
				(type default)
			)
			(layer "F.Fab")
		)
		(fp_line
			(start 0.12065 -0.3048)
			(end 0.67945 -0.3048)
			(stroke
				(width 0.1)
				(type default)
			)
			(layer "F.Fab")
		)
		(fp_line
			(start 0.120396 0.3048)
			(end 0.120396 0.2794)
			(stroke
				(width 0.1)
				(type default)
			)
			(layer "F.Fab")
		)
		(fp_line
			(start 0.120396 0.2794)
			(end -0.12065 0.2794)
			(stroke
				(width 0.1)
				(type default)
			)
			(layer "F.Fab")
		)
		(fp_line
			(start -0.12065 0.3048)
			(end -0.67945 0.3048)
			(stroke
				(width 0.1)
				(type default)
			)
			(layer "F.Fab")
		)
		(fp_line
			(start -0.12065 0.2794)
			(end -0.12065 0.3048)
			(stroke
				(width 0.1)
				(type default)
			)
			(layer "F.Fab")
		)
		(fp_line
			(start -0.12065 -0.2794)
			(end 0.12065 -0.2794)
			(stroke
				(width 0.1)
				(type default)
			)
			(layer "F.Fab")
		)
		(fp_line
			(start -0.12065 -0.305054)
			(end -0.12065 -0.2794)
			(stroke
				(width 0.1)
				(type default)
			)
			(layer "F.Fab")
		)
		(fp_line
			(start -0.67945 0.3048)
			(end -0.67945 -0.305054)
			(stroke
				(width 0.1)
				(type default)
			)
			(layer "F.Fab")
		)
		(fp_line
			(start -0.67945 -0.305054)
			(end -0.12065 -0.305054)
			(stroke
				(width 0.1)
				(type default)
			)
			(layer "F.Fab")
		)
		(pad "1" smd circle
			(at -0.40005 0 180)
			(size 0 0)
			(layers "F.Cu" "F.Mask" "F.Paste")
			(net "PVDD18_S5_P0_EN")
		)
		(pad "2" smd circle
			(at 0.40005 0 180)
			(size 0 0)
			(layers "F.Cu" "F.Mask" "F.Paste")
			(net "GND")
		)
	)
	(footprint ""
		(layer "F.Cu")
		(at 37.40658 -116.23802 90)
		(property "Reference" "Q7001"
			(at -2.4384 -3.292348 90)
			(unlocked yes)
			(layer "F.SilkS")
			(effects
				(font
					(size 0.7874 0.5842)
					(thickness 0.1524)
				)
				(justify left)
			)
		)
		(property "Value" ""
			(at 0 0 90)
			(layer "F.Fab")
			(effects
				(font
					(size 1.27 1.27)
				)
			)
		)
		(duplicate_pad_numbers_are_jumpers no)
		(fp_line
			(start 2.350008 -2.649982)
			(end 2.350008 -2.4892)
			(stroke
				(width 0.1524)
				(type default)
			)
			(layer "F.SilkS")
		)
		(fp_line
			(start -2.350008 -2.649982)
			(end 2.350008 -2.649982)
			(stroke
				(width 0.1524)
				(type default)
			)
			(layer "F.SilkS")
		)
		(fp_line
			(start -2.350008 -2.4384)
			(end -2.350008 -2.649982)
			(stroke
				(width 0.1524)
				(type default)
			)
			(layer "F.SilkS")
		)
		(fp_line
			(start 2.350008 2.4892)
			(end 2.350008 2.649982)
			(stroke
				(width 0.1524)
				(type default)
			)
			(layer "F.SilkS")
		)
		(fp_line
			(start 2.350008 2.649982)
			(end -2.350008 2.649982)
			(stroke
				(width 0.1524)
				(type default)
			)
			(layer "F.SilkS")
		)
		(fp_line
			(start -2.350008 2.649982)
			(end -2.350008 2.413)
			(stroke
				(width 0.1524)
				(type default)
			)
			(layer "F.SilkS")
		)
		(fp_poly
			(pts
				(xy -3.717544 -1.905) (xy -4.758944 -2.3241) (xy -4.758944 -1.524)
			)
			(stroke
				(width 0)
				(type default)
			)
			(fill yes)
			(layer "F.SilkS")
		)
		(fp_line
			(start 2.350008 -2.649982)
			(end 2.350008 2.649982)
			(stroke
				(width 0.1)
				(type default)
			)
			(layer "F.Fab")
		)
		(fp_line
			(start -2.350008 -2.649982)
			(end 2.350008 -2.649982)
			(stroke
				(width 0.1)
				(type default)
			)
			(layer "F.Fab")
		)
		(fp_line
			(start 2.350008 2.649982)
			(end -2.350008 2.649982)
			(stroke
				(width 0.1)
				(type default)
			)
			(layer "F.Fab")
		)
		(fp_line
			(start -2.350008 2.649982)
			(end -2.350008 -2.649982)
			(stroke
				(width 0.1)
				(type default)
			)
			(layer "F.Fab")
		)
		(fp_poly
			(pts
				(xy -3.717544 -1.905) (xy -4.758944 -2.3241) (xy -4.758944 -1.524)
			)
			(stroke
				(width 0)
				(type default)
			)
			(fill yes)
			(layer "F.Fab")
		)
		(pad "1" smd rect
			(at -2.999994 -1.905)
			(size 0.7112 1.1684)
			(layers "F.Cu" "F.Mask" "F.Paste")
			(net "GND")
		)
		(pad "2" smd rect
			(at -2.999994 -0.635)
			(size 0.7112 1.1684)
			(layers "F.Cu" "F.Mask" "F.Paste")
			(net "GND")
		)
		(pad "3" smd rect
			(at -2.999994 0.635)
			(size 0.7112 1.1684)
			(layers "F.Cu" "F.Mask" "F.Paste")
			(net "GND")
		)
		(pad "4" smd rect
			(at -2.999994 1.905)
			(size 0.7112 1.1684)
			(layers "F.Cu" "F.Mask" "F.Paste")
			(net "P12V_AUX_DSC_G2")
		)
		(pad "5" smd circle
			(at 0.925068 0)
			(size 0 0)
			(layers "F.Cu" "F.Mask" "F.Paste")
			(net "P12V_AUX_DSC")
		)
		(zone
			(layer "F.Cu")
			(hatch none 0.5)
			(connect_pads
				(clearance 0)
			)
			(min_thickness 0.25)
			(keepout
				(tracks not_allowed)
				(vias allowed)
				(pads allowed)
				(copperpour not_allowed)
				(footprints allowed)
			)
			(placement
				(enabled no)
				(sheetname "")
			)
			(fill
				(thermal_gap 0.5)
				(thermal_bridge_width 0.5)
				(island_removal_mode 0)
			)
			(polygon
				(pts
					(xy 34.76498 -118.57482) (xy 34.99358 -118.57482) (xy 34.99358 -117.88902) (xy 35.24758 -117.88902)
					(xy 35.24758 -114.79022) (xy 39.56558 -114.79022) (xy 39.56558 -117.88902) (xy 39.81958 -117.88902)
					(xy 39.81958 -118.57482) (xy 40.04818 -118.57482) (xy 40.04818 -113.88852) (xy 34.76498 -113.88852)
				)
			)
		)
	)
)
